# S9S_MB_2U (Grand Teton) — schematic netlist excerpt (pin names and nets, part order shuffled) for the footprints in the layout excerpt that follows; sources: Cadence DE-HDL packaged netlist, KiCad conversion of 03242023_DA0F0TMBIJ0_F0T_Motherboard_J_brd_V01_OCP.brd

C818  Q_CAP_DIFFBUS  DIFF BUS_0.22UF 6.3V 20% X6S  pkg C0201  page 175 : \1\ = P5E_CPU1_PE1_TX_C_DN<9> ; \2\ = P5E_CPU1_PE1_TX_DN<9>
PC555  Q_CAP  1UF 16V 10% X6S  pkg C0402  page 284 : A = PVCCIN_CPU1_VCC ; B = GND
R4186  Q_RES  1K 1% EMPTY  pkg 0402LF  page 170 : A = P3V3_AUX ; B = U272_2_ADD2

(kicad_pcb
	(version 20260206)
	(generator "pcbnew")
	(generator_version "10.0")
	(general
		(thickness 1.6)
		(legacy_teardrops no)
	)
	(paper "A4")
	(title_block
		(title "03242023_DA0F0TMBIJ0_F0T_Motherboard_J_brd_V01_OCP.brd")
		(comment 1 "Grand Teton / footprints 762-764 of 6105")
	)
	(layers
		(0 "F.Cu" signal "TOP")
		(4 "In1.Cu" signal "GND")
		(6 "In2.Cu" signal "IN1")
		(8 "In3.Cu" signal "GND1")
		(10 "In4.Cu" signal "IN2")
		(12 "In5.Cu" signal "GND2")
		(14 "In6.Cu" signal "IN3")
		(16 "In7.Cu" signal "GND3")
		(18 "In8.Cu" signal "VCC")
		(20 "In9.Cu" signal "VCC1")
		(22 "In10.Cu" signal "GND4")
		(24 "In11.Cu" signal "IN4")
		(26 "In12.Cu" signal "GND5")
		(28 "In13.Cu" signal "IN5")
		(30 "In14.Cu" signal "GND6")
		(32 "In15.Cu" signal "IN6")
		(34 "In16.Cu" signal "GND7")
		(2 "B.Cu" signal "BOTTOM")
		(9 "F.Adhes" user "F.Adhesive")
		(11 "B.Adhes" user "B.Adhesive")
		(13 "F.Paste" user "Package Geometry/Pastemask Top")
		(15 "B.Paste" user "Package Geometry/Pastemask Bottom")
		(5 "F.SilkS" user "Ref Des/Silkscreen Top")
		(7 "B.SilkS" user "Ref Des/Silkscreen Bottom")
		(1 "F.Mask" user "Board Geometry/Soldermask Top")
		(3 "B.Mask" user "Board Geometry/Soldermask Bottom")
		(17 "Dwgs.User" user "User.Drawings")
		(19 "Cmts.User" user "User.Comments")
		(21 "Eco1.User" user "User.Eco1")
		(23 "Eco2.User" user "User.Eco2")
		(25 "Edge.Cuts" user "Board Geometry/Outline")
		(27 "Margin" user)
		(31 "F.CrtYd" user "Package Geometry/Place Bound Top")
		(29 "B.CrtYd" user "Package Geometry/Place Bound Bottom")
		(35 "F.Fab" user "Ref Des/Assembly Top")
		(33 "B.Fab" user "Ref Des/Assembly Bottom")
	)
	(footprint ""
		(layer "F.Cu")
		(at 96.150938 -417.76777 90)
		(property "Reference" "R4186"
			(at 0 0 90)
			(layer "F.SilkS")
			(hide yes)
			(effects
				(font
					(size 1.27 1.27)
				)
			)
		)
		(property "Value" ""
			(at 0 0 90)
			(layer "F.Fab")
			(effects
				(font
					(size 1.27 1.27)
				)
			)
		)
		(duplicate_pad_numbers_are_jumpers no)
		(fp_line
			(start 0.7874 -0.4064)
			(end 0.7874 0.4064)
			(stroke
				(width 0.1524)
				(type default)
			)
			(layer "F.SilkS")
		)
		(fp_line
			(start -0.7874 -0.4064)
			(end 0.7874 -0.4064)
			(stroke
				(width 0.1524)
				(type default)
			)
			(layer "F.SilkS")
		)
		(fp_line
			(start 0.7874 0.4064)
			(end -0.7874 0.4064)
			(stroke
				(width 0.1524)
				(type default)
			)
			(layer "F.SilkS")
		)
		(fp_line
			(start -0.7874 0.4064)
			(end -0.7874 -0.4064)
			(stroke
				(width 0.1524)
				(type default)
			)
			(layer "F.SilkS")
		)
		(fp_line
			(start -0.12065 -0.305054)
			(end -0.12065 -0.2794)
			(stroke
				(width 0.1)
				(type default)
			)
			(layer "F.Fab")
		)
		(fp_line
			(start -0.67945 -0.305054)
			(end -0.12065 -0.305054)
			(stroke
				(width 0.1)
				(type default)
			)
			(layer "F.Fab")
		)
		(fp_line
			(start 0.67945 -0.3048)
			(end 0.67945 0.3048)
			(stroke
				(width 0.1)
				(type default)
			)
			(layer "F.Fab")
		)
		(fp_line
			(start 0.12065 -0.3048)
			(end 0.67945 -0.3048)
			(stroke
				(width 0.1)
				(type default)
			)
			(layer "F.Fab")
		)
		(fp_line
			(start 0.12065 -0.2794)
			(end 0.12065 -0.3048)
			(stroke
				(width 0.1)
				(type default)
			)
			(layer "F.Fab")
		)
		(fp_line
			(start -0.12065 -0.2794)
			(end 0.12065 -0.2794)
			(stroke
				(width 0.1)
				(type default)
			)
			(layer "F.Fab")
		)
		(fp_line
			(start 0.120396 0.2794)
			(end -0.12065 0.2794)
			(stroke
				(width 0.1)
				(type default)
			)
			(layer "F.Fab")
		)
		(fp_line
			(start -0.12065 0.2794)
			(end -0.12065 0.3048)
			(stroke
				(width 0.1)
				(type default)
			)
			(layer "F.Fab")
		)
		(fp_line
			(start 0.67945 0.3048)
			(end 0.120396 0.3048)
			(stroke
				(width 0.1)
				(type default)
			)
			(layer "F.Fab")
		)
		(fp_line
			(start 0.120396 0.3048)
			(end 0.120396 0.2794)
			(stroke
				(width 0.1)
				(type default)
			)
			(layer "F.Fab")
		)
		(fp_line
			(start -0.12065 0.3048)
			(end -0.67945 0.3048)
			(stroke
				(width 0.1)
				(type default)
			)
			(layer "F.Fab")
		)
		(fp_line
			(start -0.67945 0.3048)
			(end -0.67945 -0.305054)
			(stroke
				(width 0.1)
				(type default)
			)
			(layer "F.Fab")
		)
		(pad "1" smd circle
			(at -0.40005 0 90)
			(size 0 0)
			(layers "F.Cu" "F.Mask" "F.Paste")
			(net "P3V3_AUX")
		)
		(pad "2" smd circle
			(at 0.40005 0 90)
			(size 0 0)
			(layers "F.Cu" "F.Mask" "F.Paste")
			(net "U272_2_ADD2")
		)
	)
	(footprint ""
		(layer "F.Cu")
		(at 33.186878 -16.099536 90)
		(property "Reference" "C818"
			(at 0 0 90)
			(layer "F.SilkS")
			(hide yes)
			(effects
				(font
					(size 1.27 1.27)
				)
			)
		)
		(property "Value" ""
			(at 0 0 90)
			(layer "F.Fab")
			(effects
				(font
					(size 1.27 1.27)
				)
			)
		)
		(duplicate_pad_numbers_are_jumpers no)
		(fp_line
			(start 0.299974 -0.150114)
			(end 0.299974 0.150114)
			(stroke
				(width 0.1)
				(type default)
			)
			(layer "F.Fab")
		)
		(fp_line
			(start -0.299974 -0.150114)
			(end 0.299974 -0.150114)
			(stroke
				(width 0.1)
				(type default)
			)
			(layer "F.Fab")
		)
		(fp_line
			(start 0.299974 0.150114)
			(end -0.299974 0.150114)
			(stroke
				(width 0.1)
				(type default)
			)
			(layer "F.Fab")
		)
		(fp_line
			(start -0.299974 0.150114)
			(end -0.299974 -0.150114)
			(stroke
				(width 0.1)
				(type default)
			)
			(layer "F.Fab")
		)
		(pad "1" smd rect
			(at -0.2667 0 90)
			(size 0.3048 0.381)
			(layers "F.Cu" "F.Mask" "F.Paste")
			(net "P5E_CPU1_PE1_TX_C_DN<9>")
		)
		(pad "2" smd rect
			(at 0.2667 0 90)
			(size 0.3048 0.381)
			(layers "F.Cu" "F.Mask" "F.Paste")
			(net "P5E_CPU1_PE1_TX_DN<9>")
		)
	)
	(footprint ""
		(layer "F.Cu")
		(at 114.706654 -361.72775)
		(property "Reference" "PC555"
			(at 0 0 0)
			(layer "F.SilkS")
			(hide yes)
			(effects
				(font
					(size 1.27 1.27)
				)
			)
		)
		(property "Value" ""
			(at 0 0 0)
			(layer "F.Fab")
			(effects
				(font
					(size 1.27 1.27)
				)
			)
		)
		(duplicate_pad_numbers_are_jumpers no)
		(fp_line
			(start -0.7874 -0.4064)
			(end 0.7874 -0.4064)
			(stroke
				(width 0.1524)
				(type default)
			)
			(layer "F.SilkS")
		)
		(fp_line
			(start -0.7874 0.4064)
			(end -0.7874 -0.4064)
			(stroke
				(width 0.1524)
				(type default)
			)
			(layer "F.SilkS")
		)
		(fp_line
			(start 0.7874 -0.4064)
			(end 0.7874 0.4064)
			(stroke
				(width 0.1524)
				(type default)
			)
			(layer "F.SilkS")
		)
		(fp_line
			(start 0.7874 0.4064)
			(end -0.7874 0.4064)
			(stroke
				(width 0.1524)
				(type default)
			)
			(layer "F.SilkS")
		)
		(fp_line
			(start -0.67945 -0.305054)
			(end -0.12065 -0.305054)
			(stroke
				(width 0.1)
				(type default)
			)
			(layer "F.Fab")
		)
		(fp_line
			(start -0.67945 0.3048)
			(end -0.67945 -0.305054)
			(stroke
				(width 0.1)
				(type default)
			)
			(layer "F.Fab")
		)
		(fp_line
			(start -0.12065 -0.305054)
			(end -0.12065 -0.2794)
			(stroke
				(width 0.1)
				(type default)
			)
			(layer "F.Fab")
		)
		(fp_line
			(start -0.12065 -0.2794)
			(end 0.12065 -0.2794)
			(stroke
				(width 0.1)
				(type default)
			)
			(layer "F.Fab")
		)
		(fp_line
			(start -0.12065 0.2794)
			(end -0.12065 0.3048)
			(stroke
				(width 0.1)
				(type default)
			)
			(layer "F.Fab")
		)
		(fp_line
			(start -0.12065 0.3048)
			(end -0.67945 0.3048)
			(stroke
				(width 0.1)
				(type default)
			)
			(layer "F.Fab")
		)
		(fp_line
			(start 0.120396 0.2794)
			(end -0.12065 0.2794)
			(stroke
				(width 0.1)
				(type default)
			)
			(layer "F.Fab")
		)
		(fp_line
			(start 0.120396 0.3048)
			(end 0.120396 0.2794)
			(stroke
				(width 0.1)
				(type default)
			)
			(layer "F.Fab")
		)
		(fp_line
			(start 0.12065 -0.3048)
			(end 0.67945 -0.3048)
			(stroke
				(width 0.1)
				(type default)
			)
			(layer "F.Fab")
		)
		(fp_line
			(start 0.12065 -0.2794)
			(end 0.12065 -0.3048)
			(stroke
				(width 0.1)
				(type default)
			)
			(layer "F.Fab")
		)
		(fp_line
			(start 0.67945 -0.3048)
			(end 0.67945 0.3048)
			(stroke
				(width 0.1)
				(type default)
			)
			(layer "F.Fab")
		)
		(fp_line
			(start 0.67945 0.3048)
			(end 0.120396 0.3048)
			(stroke
				(width 0.1)
				(type default)
			)
			(layer "F.Fab")
		)
		(pad "1" smd circle
			(at -0.40005 0)
			(size 0 0)
			(layers "F.Cu" "F.Mask" "F.Paste")
			(net "PVCCIN_CPU1_VCC")
		)
		(pad "2" smd circle
			(at 0.40005 0)
			(size 0 0)
			(layers "F.Cu" "F.Mask" "F.Paste")
			(net "GND")
		)
	)
)
